# T6G (Grand Teton) — schematic parts with pin connectivity, parts 8228–8228 of 8303; source: Cadence DE-HDL packaged netlist (pstxprt.dat, pstxnet.dat, pstchip.dat)

U6011  PT5161LRS  IC  pkg BGA354_8-9X22-8  page 285
  A1  NCF_GND1  POWER  = NCF_A1_CPU0_P1_GND
  A35  NCF_GND2  POWER  = NCF_CPU0_P1_GND
  AA10  B_PETN1  OUT  = P5E_CPU0_P1_TX_BUF_DN<14>
  AA29  A_PETN1  OUT  = P5E_CPU0_P1_RX_DN<14>
  AB1  A_PERP1  IN  = P5E_CPU0_P1_RX_BUF_DP<14>
  AB35  B_PERN1  IN  = P5E_CPU0_P1_TX_C_DN<14>
  AC4  GND4  POWER  = GND
  AC13  GND1  POWER  = GND
  AC17  PWR_2A_1  POWER  = P0V9_CPU0_RT1_2A
  AC20  PWR_2A_2  POWER  = P0V9_CPU0_RT1_2A
  AC22  GND2  POWER  = GND
  AC32  GND3  POWER  = GND
  AD2  GND5  POWER  = GND
  AD34  GND6  POWER  = GND
  AE1  GND7  POWER  = GND
  AE35  GND8  POWER  = GND
  AF7  B_PETP2  OUT  = P5E_CPU0_P1_TX_BUF_DP<13>
  AF26  A_PETP2  OUT  = P5E_CPU0_P1_RX_DP<13>
  AG2  A_PERN2  IN  = P5E_CPU0_P1_RX_BUF_DN<13>
  AG34  B_PERP2  IN  = P5E_CPU0_P1_TX_C_DN<13>
  AH10  B_PETN2  OUT  = P5E_CPU0_P1_TX_BUF_DN<13>
  AH29  A_PETN2  OUT  = P5E_CPU0_P1_RX_DN<13>
  AJ1  A_PERP2  IN  = P5E_CPU0_P1_RX_BUF_DP<13>
  AJ35  B_PERN2  IN  = P5E_CPU0_P1_TX_C_DP<13>
  AK4  GND12  POWER  = GND
  AK13  GND9  POWER  = GND
  AK17  PWR_2A_3  POWER  = P0V9_CPU0_RT1_2A
  AK20  PWR_2A_4  POWER  = P0V9_CPU0_RT1_2A
  AK22  GND10  POWER  = GND
  AK32  GND11  POWER  = GND
  AL2  GND13  POWER  = GND
  AL34  GND14  POWER  = GND
  AM1  GND15  POWER  = GND
  AM35  GND16  POWER  = GND
  AN7  B_PETP3  OUT  = P5E_CPU0_P1_TX_BUF_DP<12>
  AN26  A_PETP3  OUT  = P5E_CPU0_P1_RX_DP<12>
  AP2  A_PERN3  IN  = P5E_CPU0_P1_RX_BUF_DN<12>
  AP34  B_PERP3  IN  = P5E_CPU0_P1_TX_C_DN<12>
  AR10  B_PETN3  OUT  = P5E_CPU0_P1_TX_BUF_DN<12>
  AR29  A_PETN3  OUT  = P5E_CPU0_P1_RX_DN<12>
  AT1  A_PERP3  IN  = P5E_CPU0_P1_RX_BUF_DP<12>
  AT35  B_PERN3  IN  = P5E_CPU0_P1_TX_C_DP<12>
  AU4  GND20  POWER  = GND
  AU13  GND17  POWER  = GND
  AU17  PWR_2A_5  POWER  = P0V9_CPU0_RT1_2A
  AU20  PWR_2A_6  POWER  = P0V9_CPU0_RT1_2A
  AU22  GND18  POWER  = GND
  AU32  GND19  POWER  = GND
  AV2  GND21  POWER  = GND
  AV34  GND22  POWER  = GND
  AW1  GND23  POWER  = GND
  AW35  GND24  POWER  = GND
  AY7  B_PETP4  OUT  = P5E_CPU0_P1_TX_BUF_DP<11>
  AY26  A_PETP4  OUT  = P5E_CPU0_P1_RX_DP<11>
  B3  JTAG_TCK  IN  = JTAG_TCK_RT_CPU0_P1
  B6  JTAG_TDI  IN  = JTAG_TDI_RT_CPU0_P1
  B9  JTAG_TDO  OUT  = JTAG_TDO_RT_CPU0_P1
  B12  JTAG_TMS  IN  = JTAG_TMS_RT_CPU0_P1
  B16  REFCLK_OUTP  OUT  = NC
  B19  GND25  POWER  = GND
  B23  SMB_ADDR2  IN  = RT_CPU0_P1_ADDR2
  B25  SMB_ADDR3  IN  = RT_CPU0_P1_ADDR3
  B28  SMBDAT  BI  = SMB_RT_CPU0_P1_R2_SDA
  B31  SMBCLK  BI  = SMB_RT_CPU0_P1_R2_SCL
  BA2  A_PERN4  IN  = P5E_CPU0_P1_RX_BUF_DN<11>
  BA34  B_PERP4  IN  = P5E_CPU0_P1_TX_C_DN<11>
  BB10  B_PETN4  OUT  = P5E_CPU0_P1_TX_BUF_DN<11>
  BB29  A_PETN4  OUT  = P5E_CPU0_P1_RX_DN<11>
  BC1  A_PERP4  IN  = P5E_CPU0_P1_RX_BUF_DP<11>
  BC35  B_PERN4  IN  = P5E_CPU0_P1_TX_C_DP<11>
  BD4  GND29  POWER  = GND
  BD13  GND26  POWER  = GND
  BD17  PWR_2A_7  POWER  = P0V9_CPU0_RT1_2A_2D
  BD20  PWR_2A_8  POWER  = P0V9_CPU0_RT1_2A_2D
  BD22  GND27  POWER  = GND
  BD32  GND28  POWER  = GND
  BE2  GND30  POWER  = GND
  BE34  GND31  POWER  = GND
  BF1  GND32  POWER  = GND
  BF35  GND33  POWER  = GND
  BG7  B_PETP5  OUT  = P5E_CPU0_P1_TX_BUF_DP<10>
  BG26  A_PETP5  OUT  = P5E_CPU0_P1_RX_DP<10>
  BH2  A_PERN5  IN  = P5E_CPU0_P1_RX_BUF_DN<10>
  BH34  B_PERP5  IN  = P5E_CPU0_P1_TX_C_DN<10>
  BJ10  B_PETN5  OUT  = P5E_CPU0_P1_TX_BUF_DN<10>
  BJ29  A_PETN5  OUT  = P5E_CPU0_P1_RX_DN<10>
  BK1  A_PERP5  IN  = P5E_CPU0_P1_RX_BUF_DP<10>
  BK35  B_PERN5  IN  = P5E_CPU0_P1_TX_C_DP<10>
  BL4  GND37  POWER  = GND
  BL13  GND34  POWER  = GND
  BL17  PWR_2D_1  POWER  = P0V9_CPU0_RT_2D
  BL20  PWR_2D_2  POWER  = P0V9_CPU0_RT_2D
  BL22  GND35  POWER  = GND
  BL32  GND36  POWER  = GND
  BM2  GND38  POWER  = GND
  BM34  GND39  POWER  = GND
  BN1  GND40  POWER  = GND
  BN35  GND41  POWER  = GND
  BP7  B_PETP6  OUT  = P5E_CPU0_P1_TX_BUF_DP<9>
  BP26  A_PETP6  OUT  = P5E_CPU0_P1_RX_DP<9>
  BR2  A_PERN6  IN  = P5E_CPU0_P1_RX_BUF_DN<9>
  BR34  B_PERP6  IN  = P5E_CPU0_P1_TX_C_DN<9>
  BT10  B_PETN6  OUT  = P5E_CPU0_P1_TX_BUF_DN<9>
  BT29  A_PETN6  OUT  = P5E_CPU0_P1_RX_DN<9>
  BU1  A_PERP6  IN  = P5E_CPU0_P1_RX_BUF_DP<9>
  BU35  B_PERN6  IN  = P5E_CPU0_P1_TX_C_DP<9>
  BV4  GND45  POWER  = GND
  BV13  GND42  POWER  = GND
  BV17  PWR_1D  POWER  = P1V8_CPU0_RT1_1A_1D
  BV20  PWR_1A_1  POWER  = P1V8_CPU0_RT1_1A
  BV22  GND43  POWER  = GND
  BV32  GND44  POWER  = GND
  BW2  GND46  POWER  = GND
  BW34  GND47  POWER  = GND
  BY1  GND48  POWER  = GND
  BY35  GND49  POWER  = GND
  C2  NCF_GND3  POWER  = NCF_CPU0_P1_GND
  C34  NCF_GND4  POWER  = NCF_CPU0_P1_GND
  CA7  B_PETP7  OUT  = P5E_CPU0_P1_TX_BUF_DP<8>
  CA26  A_PETP7  OUT  = P5E_CPU0_P1_RX_DP<8>
  CB2  A_PERN7  IN  = P5E_CPU0_P1_RX_BUF_DN<8>
  CB34  B_PERP7  IN  = P5E_CPU0_P1_TX_C_DN<8>
  CC10  B_PETN7  OUT  = P5E_CPU0_P1_TX_BUF_DN<8>
  CC29  A_PETN7  OUT  = P5E_CPU0_P1_RX_DN<8>
  CD1  A_PERP7  IN  = P5E_CPU0_P1_RX_BUF_DP<8>
  CD35  B_PERN7  IN  = P5E_CPU0_P1_TX_C_DP<8>
  CE4  GND53  POWER  = GND
  CE13  GND50  POWER  = GND
  CE17  PWR_1A_2  POWER  = P1V8_CPU0_RT1_1A
  CE20  PWR_1A_3  POWER  = P1V8_CPU0_RT1_1A
  CE22  GND51  POWER  = GND
  CE32  GND52  POWER  = GND
  CF2  GND54  POWER  = GND
  CF34  GND55  POWER  = GND
  CG1  GND56  POWER  = GND
  CG35  GND57  POWER  = GND
  CH7  B_PETP8  OUT  = P5E_CPU0_P1_TX_BUF_DP<7>
  CH26  A_PETP8  OUT  = P5E_CPU0_P1_RX_DP<7>
  CJ2  A_PERN8  IN  = P5E_CPU0_P1_RX_BUF_DN<7>
  CJ34  B_PERP8  IN  = P5E_CPU0_P1_TX_C_DN<7>
  CK10  B_PETN8  OUT  = P5E_CPU0_P1_TX_BUF_DN<7>
  CK29  A_PETN8  OUT  = P5E_CPU0_P1_RX_DN<7>
  CL1  A_PERP8  IN  = P5E_CPU0_P1_RX_BUF_DP<7>
  CL35  B_PERN8  IN  = P5E_CPU0_P1_TX_C_DP<7>
  CM4  GND61  POWER  = GND
  CM13  GND58  POWER  = GND
  CM17  PWR_1A_4  POWER  = P1V8_CPU0_RT1_1A
  CM20  PWR_1A_5  POWER  = P1V8_CPU0_RT1_1A
  CM22  GND59  POWER  = GND
  CM32  GND60  POWER  = GND
  CN2  GND62  POWER  = GND
  CN34  GND63  POWER  = GND
  CP1  GND64  POWER  = GND
  CP35  GND65  POWER  = GND
  CR7  B_PETP9  OUT  = P5E_CPU0_P1_TX_BUF_DP<6>
  CR26  A_PETP9  OUT  = P5E_CPU0_P1_RX_DP<6>
  CT2  A_PERN9  IN  = P5E_CPU0_P1_RX_BUF_DN<6>
  CT34  B_PERP9  IN  = P5E_CPU0_P1_TX_C_DN<6>
  CU10  B_PETN9  OUT  = P5E_CPU0_P1_TX_BUF_DN<6>
  CU29  A_PETN9  OUT  = P5E_CPU0_P1_RX_DN<6>
  CV1  A_PERP9  IN  = P5E_CPU0_P1_RX_BUF_DP<6>
  CV35  B_PERN9  IN  = P5E_CPU0_P1_TX_C_DP<6>
  CW4  GND69  POWER  = GND
  CW13  GND66  POWER  = GND
  CW17  PWR_2D_3  POWER  = P0V9_CPU0_RT_2D
  CW20  PWR_2D_4  POWER  = P0V9_CPU0_RT_2D
  CW22  GND67  POWER  = GND
  CW32  GND68  POWER  = GND
  CY2  GND70  POWER  = GND
  CY34  GND71  POWER  = GND
  D1  NCF_GND5  POWER  = NCF_CPU0_P1_GND
  D35  NCF_GND6  POWER  = NCF_CPU0_P1_GND
  DA1  GND72  POWER  = GND
  DA35  GND73  POWER  = GND
  DB7  B_PETP10  OUT  = P5E_CPU0_P1_TX_BUF_DP<5>
  DB26  A_PETP10  OUT  = P5E_CPU0_P1_RX_DP<5>
  DC2  A_PERN10  IN  = P5E_CPU0_P1_RX_BUF_DN<5>
  DC34  B_PERP10  IN  = P5E_CPU0_P1_TX_C_DN<5>
  DD10  B_PETN10  OUT  = P5E_CPU0_P1_TX_BUF_DN<5>
  DD29  A_PETN10  OUT  = P5E_CPU0_P1_RX_DN<5>
  DE1  A_PERP10  IN  = P5E_CPU0_P1_RX_BUF_DP<5>
  DE35  B_PERN10  IN  = P5E_CPU0_P1_TX_C_DP<5>
  DF4  GND77  POWER  = GND
  DF13  GND74  POWER  = GND
  DF17  PWR_2A_9  POWER  = P0V9_CPU0_RT1_2A_2D
  DF20  PWR_2A_10  POWER  = P0V9_CPU0_RT1_2A_2D
  DF22  GND75  POWER  = GND
  DF32  GND76  POWER  = GND
  DG2  GND78  POWER  = GND
  DG34  GND79  POWER  = GND
  DH1  GND80  POWER  = GND
  DH35  GND81  POWER  = GND
  DJ7  B_PETP11  OUT  = P5E_CPU0_P1_TX_BUF_DP<4>
  DJ26  A_PETP11  OUT  = P5E_CPU0_P1_RX_DP<4>
  DK2  A_PERN11  IN  = P5E_CPU0_P1_RX_BUF_DN<4>
  DK34  B_PERP11  IN  = P5E_CPU0_P1_TX_C_DN<4>
  DL10  B_PETN11  OUT  = P5E_CPU0_P1_TX_BUF_DN<4>
  DL29  A_PETN11  OUT  = P5E_CPU0_P1_RX_DN<4>
  DM1  A_PERP11  IN  = P5E_CPU0_P1_RX_BUF_DP<4>
  DM35  B_PERN11  IN  = P5E_CPU0_P1_TX_C_DP<4>
  DN4  GND85  POWER  = GND
  DN13  GND82  POWER  = GND
  DN17  PWR_2A_11  POWER  = P0V9_CPU0_RT1_2A
  DN20  PWR_2A_12  POWER  = P0V9_CPU0_RT1_2A
  DN22  GND83  POWER  = GND
  DN32  GND84  POWER  = GND
  DP2  GND86  POWER  = GND
  DP34  GND87  POWER  = GND
  DR1  GND88  POWER  = GND
  DR35  GND89  POWER  = GND
  DT7  B_PETP12  OUT  = P5E_CPU0_P1_TX_BUF_DP<3>
  DT26  A_PETP12  OUT  = P5E_CPU0_P1_RX_DP<3>
  DU2  A_PERN12  IN  = P5E_CPU0_P1_RX_BUF_DN<3>
  DU34  B_PERP12  IN  = P5E_CPU0_P1_TX_C_DN<3>
  DV10  B_PETN12  OUT  = P5E_CPU0_P1_TX_BUF_DN<3>
  DV29  A_PETN12  OUT  = P5E_CPU0_P1_RX_DN<3>
  DW1  A_PERP12  IN  = P5E_CPU0_P1_RX_BUF_DP<3>
  DW35  B_PERN12  IN  = P5E_CPU0_P1_TX_C_DP<3>
  DY4  GND93  POWER  = GND
  DY13  GND90  POWER  = GND
  DY17  PWR_2A_13  POWER  = P0V9_CPU0_RT1_2A
  DY20  PWR_2A_14  POWER  = P0V9_CPU0_RT1_2A
  DY22  GND91  POWER  = GND
  DY32  GND92  POWER  = GND
  E8  JTAG_TRST_N  IN  = JTAG_TRST_RT_CPU0_P1_N
  E11  RXDET_BYP  IN  = RXDET_BYP_RT_CPU0_P1
  E14  GND94  POWER  = GND
  E18  REFCLK_OUTN  OUT  = NC
  E27  GND95  POWER  = GND
  E30  T_SENSE  OUT  = GND
  E33  GND96  POWER  = GND
  EA2  GND97  POWER  = GND
  EA34  GND98  POWER  = GND
  EB1  GND99  POWER  = GND
  EB35  GND100  POWER  = GND
  EC7  B_PETP13  OUT  = P5E_CPU0_P1_TX_BUF_DP<2>
  EC26  A_PETP13  OUT  = P5E_CPU0_P1_RX_DP<2>
  ED2  A_PERN13  IN  = P5E_CPU0_P1_RX_BUF_DN<2>
  ED34  B_PERP13  IN  = P5E_CPU0_P1_TX_C_DN<2>
  EE10  B_PETN13  OUT  = P5E_CPU0_P1_TX_BUF_DN<2>
  EE29  A_PETN13  OUT  = P5E_CPU0_P1_RX_DN<2>
  EF1  A_PERP13  IN  = P5E_CPU0_P1_RX_BUF_DP<2>
  EF35  B_PERN13  IN  = P5E_CPU0_P1_TX_C_DP<2>
  EG4  GND104  POWER  = GND
  EG13  GND101  POWER  = GND
  EG17  PWR_2A_15  POWER  = P0V9_CPU0_RT1_2A
  EG20  PWR_2A_16  POWER  = P0V9_CPU0_RT1_2A
  EG22  GND102  POWER  = GND
  EG32  GND103  POWER  = GND
  EH2  GND105  POWER  = GND
  EH34  GND106  POWER  = GND
  EJ1  GND107  POWER  = GND
  EJ35  GND108  POWER  = GND
  EK7  B_PETP14  OUT  = P5E_CPU0_P1_TX_BUF_DP<1>
  EK26  A_PETP14  OUT  = P5E_CPU0_P1_RX_DP<1>
  EL2  A_PERN14  IN  = P5E_CPU0_P1_RX_BUF_DN<1>
  EL34  B_PERP14  IN  = P5E_CPU0_P1_TX_C_DP<1>
  EM10  B_PETN14  OUT  = P5E_CPU0_P1_TX_BUF_DN<1>
  EM29  A_PETN14  OUT  = P5E_CPU0_P1_RX_DN<1>
  EN1  A_PERP14  IN  = P5E_CPU0_P1_RX_BUF_DP<1>
  EN35  B_PERN14  IN  = P5E_CPU0_P1_TX_C_DN<1>
  EP4  GND112  POWER  = GND
  EP13  GND109  POWER  = GND
  EP17  PWR_2A_17  POWER  = P0V9_CPU0_RT1_2A
  EP20  PWR_2A_18  POWER  = P0V9_CPU0_RT1_2A
  EP22  GND110  POWER  = GND
  EP32  GND111  POWER  = GND
  ER2  GND113  POWER  = GND
  ER34  GND114  POWER  = GND
  ET1  GND115  POWER  = GND
  ET35  GND116  POWER  = GND
  EU7  B_PETP15  OUT  = P5E_CPU0_P1_TX_BUF_DP<0>
  EU26  A_PETP15  OUT  = P5E_CPU0_P1_RX_DP<0>
  EV2  A_PERN15  IN  = P5E_CPU0_P1_RX_BUF_DN<0>
  EV34  B_PERP15  IN  = P5E_CPU0_P1_TX_C_DN<0>
  EW10  B_PETN15  OUT  = P5E_CPU0_P1_TX_BUF_DN<0>
  EW29  A_PETN15  OUT  = P5E_CPU0_P1_RX_DN<0>
  EY1  A_PERP15  IN  = P5E_CPU0_P1_RX_BUF_DP<0>
  EY35  B_PERN15  IN  = P5E_CPU0_P1_TX_C_DP<0>
  F2  PERST_N  IN  = RST_RT_CPU0_P1_PERST_N
  F34  SMB_ADDR1  IN  = RT_CPU0_P1_ADDR1
  FA15  GND117  POWER  = GND
  FA32  GND118  POWER  = GND
  FB2  GND119  POWER  = GND
  FB34  GND120  POWER  = GND
  FC3  GND125  POWER  = GND
  FC6  GND126  POWER  = GND
  FC9  GND127  POWER  = GND
  FC19  GND121  POWER  = GND
  FC23  GND122  POWER  = GND
  FC25  GND123  POWER  = GND
  FC28  GND124  POWER  = GND
  FD1  GND128  POWER  = GND
  FD35  GND129  POWER  = GND
  FE2  NCF_GND7  POWER  = NCF_CPU0_P1_GND
  FE34  NCF_GND8  POWER  = NCF_CPU0_P1_GND
  FF5  EE_CLK  BI  = SMB_RT_CPU0_P1_ROM_MUX_1D_R_SCL
  FF8  JTAG_TEST_MODE  IN  = JTAG_TEST_MODE_RT_CPU0_P1
  FF11  RESET_N  IN  = RST_RT_CPU0_P1_RESET_N
  FF14  GND130  POWER  = GND
  FF18  REFCLKN  IN  = CLK_100M_RETIMER_CPU0_P1_DN
  FF21  GND131  POWER  = GND
  FF24  TEST0  BI  = TEST0_RT_CPU0_P1
  FF27  TEST1  BI  = TEST1_RT_CPU0_P1
  FF30  TEST2  BI  = TEST2_RT_CPU0_P1
  FF33  SCAN_MODE  IN  = RT_CPU0_P1_SCAN_MODE
  FG1  NCF_GND9  POWER  = NCF_CPU0_P1_GND
  FG35  NCF_GND10  POWER  = NCF_CPU0_P1_GND
  FH2  NCF_GND11  POWER  = NCF_CPU0_P1_GND
  FH34  NCF_GND12  POWER  = NCF_CPU0_P1_GND
  FJ3  EE_DAT  BI  = SMB_RT_CPU0_P1_ROM_MUX_1D_R_SDA
  FJ6  GPIO0  BI  = NC
  FJ9  MODE  IN  = MODE_RT_CPU0_P1
  FJ12  GND132  POWER  = GND
  FJ16  REFCLKP  IN  = CLK_100M_RETIMER_CPU0_P1_DP
  FJ19  GND133  POWER  = GND
  FJ23  GPIO1  BI  = NC
  FJ25  GPIO2  BI  = GPIO2_RT_CPU0_P1
  FJ28  GPIO3  BI  = GPIO3_RT_CPU0_P1
  FJ31  INT_N  OUT  = NC
  G1  VQPS  IN  = RT_CPU0_P1_VQPS
  G35  CLKREQ_N  IN  = CLKREQ_RT_CPU0_P1_N
  H12  GND134  POWER  = GND
  H16  GND135  POWER  = GND
  H19  GND136  POWER  = GND
  H31  GND137  POWER  = GND
  J4  GND139  POWER  = GND
  J22  GND138  POWER  = GND
  K2  GND140  POWER  = GND
  K34  GND141  POWER  = GND
  L1  GND142  POWER  = GND
  L35  GND143  POWER  = GND
  M7  B_PETP0  OUT  = P5E_CPU0_P1_TX_BUF_DP<15>
  M26  A_PETP0  OUT  = P5E_CPU0_P1_RX_DP<15>
  N2  A_PERN0  IN  = P5E_CPU0_P1_RX_BUF_DN<15>
  N34  B_PERP0  IN  = P5E_CPU0_P1_TX_C_DN<15>
  P10  B_PETN0  OUT  = P5E_CPU0_P1_TX_BUF_DN<15>
  P29  A_PETN0  OUT  = P5E_CPU0_P1_RX_DN<15>
  R1  A_PERP0  IN  = P5E_CPU0_P1_RX_BUF_DP<15>
  R35  B_PERN0  IN  = P5E_CPU0_P1_TX_C_DP<15>
  T4  GND147  POWER  = GND
  T13  GND144  POWER  = GND
  T17  PWR_2A_19  POWER  = P0V9_CPU0_RT1_2A
  T20  PWR_2A_20  POWER  = P0V9_CPU0_RT1_2A
  T22  GND145  POWER  = GND
  T32  GND146  POWER  = GND
  U2  GND148  POWER  = GND
  U34  GND149  POWER  = GND
  V1  GND150  POWER  = GND
  V35  GND151  POWER  = GND
  W7  B_PETP1  OUT  = P5E_CPU0_P1_TX_BUF_DP<14>
  W26  A_PETP1  OUT  = P5E_CPU0_P1_RX_DP<14>
  Y2  A_PERN1  IN  = P5E_CPU0_P1_RX_BUF_DN<14>
  Y34  B_PERP1  IN  = P5E_CPU0_P1_TX_C_DP<14>
